# T6G (Grand Teton) — schematic netlist excerpt (pin names and nets, part order shuffled) for the footprints in the layout excerpt that follows; sources: Cadence DE-HDL packaged netlist, KiCad conversion of 04192023_DAF0TMB3IC0_F0TG_MB_C_brd_V02_OCP.brd

PR1131  Q_RES  2K 0.1% CHIP  pkg 0402LF  page 262 : A = HSC_CS ; B = AGND_HSC
PC6800  Q_CAPP  270UF 16V 20% OSCON  pkg SMLF  page 360 : A = SW_P12V_AUX_P1V8_RETIMER_CPU0_FLT ; B = GND

(kicad_pcb
	(version 20260206)
	(generator "pcbnew")
	(generator_version "10.0")
	(general
		(thickness 1.6)
		(legacy_teardrops no)
	)
	(paper "A4")
	(title_block
		(title "04192023_DAF0TMB3IC0_F0TG_MB_C_brd_V02_OCP.brd")
		(comment 1 "Grand Teton / footprints 1418-1419 of 8354")
	)
	(layers
		(0 "F.Cu" signal "TOP")
		(4 "In1.Cu" signal "GND")
		(6 "In2.Cu" signal "IN1")
		(8 "In3.Cu" signal "GND1")
		(10 "In4.Cu" signal "IN2")
		(12 "In5.Cu" signal "GND2")
		(14 "In6.Cu" signal "IN3")
		(16 "In7.Cu" signal "GND3")
		(18 "In8.Cu" signal "VCC")
		(20 "In9.Cu" signal "VCC1")
		(22 "In10.Cu" signal "GND4")
		(24 "In11.Cu" signal "IN4")
		(26 "In12.Cu" signal "GND5")
		(28 "In13.Cu" signal "IN5")
		(30 "In14.Cu" signal "GND6")
		(32 "In15.Cu" signal "IN6")
		(34 "In16.Cu" signal "GND7")
		(2 "B.Cu" signal "BOTTOM")
		(9 "F.Adhes" user "F.Adhesive")
		(11 "B.Adhes" user "B.Adhesive")
		(13 "F.Paste" user "Package Geometry/Pastemask Top")
		(15 "B.Paste" user "Package Geometry/Pastemask Bottom")
		(5 "F.SilkS" user "Ref Des/Silkscreen Top")
		(7 "B.SilkS" user "Ref Des/Silkscreen Bottom")
		(1 "F.Mask" user "Board Geometry/Soldermask Top")
		(3 "B.Mask" user "Board Geometry/Soldermask Bottom")
		(17 "Dwgs.User" user "User.Drawings")
		(19 "Cmts.User" user "User.Comments")
		(21 "Eco1.User" user "User.Eco1")
		(23 "Eco2.User" user "User.Eco2")
		(25 "Edge.Cuts" user "Board Geometry/Outline")
		(27 "Margin" user)
		(31 "F.CrtYd" user "Package Geometry/Place Bound Top")
		(29 "B.CrtYd" user "Package Geometry/Place Bound Bottom")
		(35 "F.Fab" user "Ref Des/Assembly Top")
		(33 "B.Fab" user "Ref Des/Assembly Bottom")
	)
	(footprint ""
		(layer "F.Cu")
		(at 248.210578 -277.433532)
		(property "Reference" "PC6800"
			(at -1.068578 -4.352798 0)
			(unlocked yes)
			(layer "F.SilkS")
			(effects
				(font
					(size 0.7874 0.5842)
					(thickness 0.1524)
				)
				(justify left)
			)
		)
		(property "Value" ""
			(at 0 0 0)
			(layer "F.Fab")
			(effects
				(font
					(size 1.27 1.27)
				)
			)
		)
		(duplicate_pad_numbers_are_jumpers no)
		(fp_line
			(start -3.400044 -2.146046)
			(end -3.400044 -0.9398)
			(stroke
				(width 0.1524)
				(type default)
			)
			(layer "F.SilkS")
		)
		(fp_line
			(start -3.400044 2.146046)
			(end -3.400044 0.9398)
			(stroke
				(width 0.1524)
				(type default)
			)
			(layer "F.SilkS")
		)
		(fp_line
			(start -2.146046 -3.400044)
			(end -3.400044 -2.146046)
			(stroke
				(width 0.1524)
				(type default)
			)
			(layer "F.SilkS")
		)
		(fp_line
			(start -2.146046 3.400044)
			(end -3.400044 2.146046)
			(stroke
				(width 0.1524)
				(type default)
			)
			(layer "F.SilkS")
		)
		(fp_line
			(start 3.400044 -3.400044)
			(end -2.146046 -3.400044)
			(stroke
				(width 0.1524)
				(type default)
			)
			(layer "F.SilkS")
		)
		(fp_line
			(start 3.400044 -0.9398)
			(end 3.400044 -3.400044)
			(stroke
				(width 0.1524)
				(type default)
			)
			(layer "F.SilkS")
		)
		(fp_line
			(start 3.400044 0.9398)
			(end 3.400044 3.400044)
			(stroke
				(width 0.1524)
				(type default)
			)
			(layer "F.SilkS")
		)
		(fp_line
			(start 3.400044 3.400044)
			(end -2.146046 3.400044)
			(stroke
				(width 0.1524)
				(type default)
			)
			(layer "F.SilkS")
		)
		(fp_line
			(start -3.400044 -3.400044)
			(end -3.400044 3.400044)
			(stroke
				(width 0.1)
				(type default)
			)
			(layer "F.Fab")
		)
		(fp_line
			(start -3.400044 3.400044)
			(end 3.400044 3.400044)
			(stroke
				(width 0.1)
				(type default)
			)
			(layer "F.Fab")
		)
		(fp_line
			(start 3.400044 -3.400044)
			(end -3.400044 -3.400044)
			(stroke
				(width 0.1)
				(type default)
			)
			(layer "F.Fab")
		)
		(fp_line
			(start 3.400044 3.400044)
			(end 3.400044 -3.400044)
			(stroke
				(width 0.1)
				(type default)
			)
			(layer "F.Fab")
		)
		(pad "1" smd rect
			(at -2.70002 0 270)
			(size 1.6002 3.5052)
			(layers "F.Cu" "F.Mask" "F.Paste")
			(net "SW_P12V_AUX_P1V8_RETIMER_CPU0_FLT")
		)
		(pad "2" smd rect
			(at 2.70002 0 270)
			(size 1.6002 3.5052)
			(layers "F.Cu" "F.Mask" "F.Paste")
			(net "GND")
		)
	)
	(footprint ""
		(layer "F.Cu")
		(at 178.71694 -399.420842 180)
		(property "Reference" "PR1131"
			(at 0 0 180)
			(layer "F.SilkS")
			(hide yes)
			(effects
				(font
					(size 1.27 1.27)
				)
			)
		)
		(property "Value" ""
			(at 0 0 180)
			(layer "F.Fab")
			(effects
				(font
					(size 1.27 1.27)
				)
			)
		)
		(duplicate_pad_numbers_are_jumpers no)
		(fp_line
			(start 0.7874 0.4064)
			(end -0.7874 0.4064)
			(stroke
				(width 0.1524)
				(type default)
			)
			(layer "F.SilkS")
		)
		(fp_line
			(start 0.7874 -0.4064)
			(end 0.7874 0.4064)
			(stroke
				(width 0.1524)
				(type default)
			)
			(layer "F.SilkS")
		)
		(fp_line
			(start -0.7874 0.4064)
			(end -0.7874 -0.4064)
			(stroke
				(width 0.1524)
				(type default)
			)
			(layer "F.SilkS")
		)
		(fp_line
			(start -0.7874 -0.4064)
			(end 0.7874 -0.4064)
			(stroke
				(width 0.1524)
				(type default)
			)
			(layer "F.SilkS")
		)
		(fp_line
			(start 0.67945 0.3048)
			(end 0.120396 0.3048)
			(stroke
				(width 0.1)
				(type default)
			)
			(layer "F.Fab")
		)
		(fp_line
			(start 0.67945 -0.3048)
			(end 0.67945 0.3048)
			(stroke
				(width 0.1)
				(type default)
			)
			(layer "F.Fab")
		)
		(fp_line
			(start 0.12065 -0.2794)
			(end 0.12065 -0.3048)
			(stroke
				(width 0.1)
				(type default)
			)
			(layer "F.Fab")
		)
		(fp_line
			(start 0.12065 -0.3048)
			(end 0.67945 -0.3048)
			(stroke
				(width 0.1)
				(type default)
			)
			(layer "F.Fab")
		)
		(fp_line
			(start 0.120396 0.3048)
			(end 0.120396 0.2794)
			(stroke
				(width 0.1)
				(type default)
			)
			(layer "F.Fab")
		)
		(fp_line
			(start 0.120396 0.2794)
			(end -0.12065 0.2794)
			(stroke
				(width 0.1)
				(type default)
			)
			(layer "F.Fab")
		)
		(fp_line
			(start -0.12065 0.3048)
			(end -0.67945 0.3048)
			(stroke
				(width 0.1)
				(type default)
			)
			(layer "F.Fab")
		)
		(fp_line
			(start -0.12065 0.2794)
			(end -0.12065 0.3048)
			(stroke
				(width 0.1)
				(type default)
			)
			(layer "F.Fab")
		)
		(fp_line
			(start -0.12065 -0.2794)
			(end 0.12065 -0.2794)
			(stroke
				(width 0.1)
				(type default)
			)
			(layer "F.Fab")
		)
		(fp_line
			(start -0.12065 -0.305054)
			(end -0.12065 -0.2794)
			(stroke
				(width 0.1)
				(type default)
			)
			(layer "F.Fab")
		)
		(fp_line
			(start -0.67945 0.3048)
			(end -0.67945 -0.305054)
			(stroke
				(width 0.1)
				(type default)
			)
			(layer "F.Fab")
		)
		(fp_line
			(start -0.67945 -0.305054)
			(end -0.12065 -0.305054)
			(stroke
				(width 0.1)
				(type default)
			)
			(layer "F.Fab")
		)
		(pad "1" smd circle
			(at -0.40005 0 180)
			(size 0 0)
			(layers "F.Cu" "F.Mask" "F.Paste")
			(net "HSC_CS")
		)
		(pad "2" smd circle
			(at 0.40005 0 180)
			(size 0 0)
			(layers "F.Cu" "F.Mask" "F.Paste")
			(net "AGND_HSC")
		)
	)
)
